FILE_TYPE = MULTI_PHYS_TABLE;

PART 'MOSFET_N'

{========================================================================================}
:VALUE          | MANUF_PN       | PACK_TYPE | MATERIAL | PART_NUMBER       = STANDARD        | LIFECYCLE      | PART_NUMBER       | JEDEC_TYPE    | CLASS | DESCRIPTION                              | COMPONENT_TYPE | LEAD_LENGTH | LPID | DAY        ;
{========================================================================================}
 '2N7002LT1'    | '2N7002LT1'    | 'SMLF'    | 'IC'     | 'BAN70020T04'(!)  = 'End of Design' | 'Comp-Approve' | 'BAN70020T04'     |'SOT23_GDS'| 'IC'  | 'TRANSISTOR MOSFET 2N7002(60V,0.115A)'   | 'SMALLSMT'     | ''          | ''   | '20100709'
 '2N7002LT1'    | '2N7002LT1'    | 'SMLF'    | 'EMPTY'  | 'BAN70020T04'(!)  = 'End of Design' | 'Comp-Approve' | 'BAN70020T04'     |'SOT23_GDS'| 'IO'  | 'TRANSISTOR MOSFET 2N7002(60V,0.115A)'   | 'SMALLSMT'     | ''          | ''   | '20100709'
 '2N7002-T1-E3' | '2N7002-T1-E3' | 'SMLF'    | 'IC'     | 'BAN70020050'(!)  = 'End of Design' | 'Comp-Approve' | 'BAN70020050'     |'SOT23_GDS'| 'IC'  | 'TRANS MOSFET 2N7002-T1-E3(60V,0.115A)'  | 'SMALLSMT'     | ''          | ''   | '20100709'
 '2N7002-T1-E3' | '2N7002-T1-E3' | 'SMLF'    | 'EMPTY'  | 'BAN70020050'(!)  = 'End of Design' | 'Comp-Approve' | 'BAN70020050'     |'SOT23_GDS'| 'IO'  | 'TRANS MOSFET 2N7002-T1-E3(60V,0.115A)'  | 'SMALLSMT'     | ''          | ''   | '20100709'
 'BSS138K'      | 'BSS138K'      | 'SMLF'    | 'IC'     | 'BAM138K0000'(!)  = 'End of Design' | 'Comp-Approve' | 'BAM138K0000'     |'SOT23_GDSXD'| 'IC'  | 'TRANS MOS BSS138K(50V,0.22A,0.35W)'     | 'SMALLSMT'     | ''          | ''   | '20150826'
 'BSS138K'      | 'BSS138K'      | 'SMLF'    | 'EMPTY'  | 'BAM138K0000'(!)  = 'End of Design' | 'Comp-Approve' | 'BAM138K0000'     |'SOT23_GDSXD'| 'IO'  | 'TRANS MOS BSS138K(50V,0.22A,0.35W)'     | 'SMALLSMT'     | ''          | ''   | '20150826'
 'BSS138K'      | 'BSS138K'      | 'SMLF'    | 'IC'     | 'BAM138K0000SEL1'(!) = ''              | ''               | 'BAM138K0000SEL1' |'SOT23_GDSXD'| 'IC'  | 'TRANS MOS BSS138K(50V,0.22A,0.35W)SELA' | 'SMALLSMT'     | ''          | ''   | '20230626'
 'BSS138K'      | 'BSS138K'      | 'SMLF'    | 'EMPTY'  | 'BAM138K0000SEL1'(!) = ''              | ''               | 'BAM138K0000SEL1' |'SOT23_GDSXD'| 'IO'  | 'TRANS MOS BSS138K(50V,0.22A,0.35W)SELA' | 'SMALLSMT'     | ''          | ''   | '20230626'

END_PART

END.

